# BASEBOARD_FAB2 (Tioga Pass) — schematic netlist excerpt (pin names and nets, part order shuffled) for the footprints in the layout excerpt that follows; sources: Cadence DE-HDL packaged netlist, KiCad conversion of Wiwynn_Tioga_Pass_MB.brd

R25W70  RES  33.2 1% CHIP  pkg 0402  page 144 : A = FM_CPU0_FIVR_FAULT_LVT3_R_N ; B = FM_CPU0_FIVR_FAULT_LVT3_N
C5P39  CAP  100UF 4V 20% X5R  pkg 0805  page 217 : A = PVDDQ_ABC ; B = GND
R1T3  RES  665 1.0% CHIP  pkg 0402  page 160 : A = P3V3_STBY ; B = SMB_SLOTX24_STBY_LVC3_SDA_R

(kicad_pcb
	(version 20260206)
	(generator "pcbnew")
	(generator_version "10.0")
	(general
		(thickness 1.6)
		(legacy_teardrops no)
	)
	(paper "A4")
	(title_block
		(title "Wiwynn_Tioga_Pass_MB.brd")
		(comment 1 "Tioga Pass / footprints 4426-4428 of 4770")
	)
	(layers
		(0 "F.Cu" signal "TOP")
		(4 "In1.Cu" signal "L2GND")
		(6 "In2.Cu" signal "L3")
		(8 "In3.Cu" signal "L4GND")
		(10 "In4.Cu" signal "L5")
		(12 "In5.Cu" signal "L6GND")
		(14 "In6.Cu" signal "L7VCC")
		(16 "In7.Cu" signal "L8VCC")
		(18 "In8.Cu" signal "L9GND")
		(20 "In9.Cu" signal "L10")
		(22 "In10.Cu" signal "L11GND")
		(24 "In11.Cu" signal "L12")
		(26 "In12.Cu" signal "L13GND")
		(2 "B.Cu" signal "BOTTOM")
		(9 "F.Adhes" user "F.Adhesive")
		(11 "B.Adhes" user "B.Adhesive")
		(13 "F.Paste" user "Package Geometry/Pastemask Top")
		(15 "B.Paste" user "Package Geometry/Pastemask Bottom")
		(5 "F.SilkS" user "Ref Des/Silkscreen Top")
		(7 "B.SilkS" user "Ref Des/Silkscreen Bottom")
		(1 "F.Mask" user "Board Geometry/Soldermask Top")
		(3 "B.Mask" user "Board Geometry/Soldermask Bottom")
		(17 "Dwgs.User" user "User.Drawings")
		(19 "Cmts.User" user "User.Comments")
		(21 "Eco1.User" user "User.Eco1")
		(23 "Eco2.User" user "User.Eco2")
		(25 "Edge.Cuts" user "Board Geometry/Outline")
		(27 "Margin" user)
		(31 "F.CrtYd" user "Package Geometry/Place Bound Top")
		(29 "B.CrtYd" user "Package Geometry/Place Bound Bottom")
		(35 "F.Fab" user "Ref Des/Assembly Top")
		(33 "B.Fab" user "Ref Des/Assembly Bottom")
	)
	(footprint ""
		(layer "B.Cu")
		(at 419.887146 -48.160432 90)
		(property "Reference" "R1T3"
			(at 0 0 90)
			(layer "B.SilkS")
			(hide yes)
			(effects
				(font
					(size 1.27 1.27)
				)
				(justify mirror)
			)
		)
		(property "Value" ""
			(at 0 0 90)
			(layer "B.Fab")
			(effects
				(font
					(size 1.27 1.27)
				)
				(justify mirror)
			)
		)
		(duplicate_pad_numbers_are_jumpers no)
		(fp_poly
			(pts
				(xy 0.2794 -0.1016) (xy -0.2794 -0.1016) (xy -0.2794 0.9906) (xy 0.2794 0.9906)
			)
			(stroke
				(width 0)
				(type default)
			)
			(fill no)
			(layer "B.CrtYd")
		)
		(fp_line
			(start 0.2794 -0.1016)
			(end 0.2794 0.9906)
			(stroke
				(width 0.1)
				(type default)
			)
			(layer "B.Fab")
		)
		(fp_line
			(start -0.2794 -0.1016)
			(end 0.2794 -0.1016)
			(stroke
				(width 0.1)
				(type default)
			)
			(layer "B.Fab")
		)
		(fp_line
			(start 0.2794 0.9906)
			(end -0.2794 0.9906)
			(stroke
				(width 0.1)
				(type default)
			)
			(layer "B.Fab")
		)
		(fp_line
			(start -0.2794 0.9906)
			(end -0.2794 -0.1016)
			(stroke
				(width 0.1)
				(type default)
			)
			(layer "B.Fab")
		)
		(pad "1" smd rect
			(at 0 0 270)
			(size 0.508 0.508)
			(layers "B.Cu" "B.Mask" "B.Paste")
			(net "P3V3_STBY")
		)
		(pad "2" smd rect
			(at 0 0.889 270)
			(size 0.508 0.508)
			(layers "B.Cu" "B.Mask" "B.Paste")
			(net "SMB_SLOTX24_STBY_LVC3_SDA_R")
		)
		(zone
			(layer "B.Cu")
			(hatch none 0.5)
			(connect_pads
				(clearance 0)
			)
			(min_thickness 0.25)
			(keepout
				(tracks allowed)
				(vias not_allowed)
				(pads allowed)
				(copperpour not_allowed)
				(footprints allowed)
			)
			(placement
				(enabled no)
				(sheetname "")
			)
			(fill
				(thermal_gap 0.5)
				(thermal_bridge_width 0.5)
				(island_removal_mode 0)
			)
			(polygon
				(pts
					(xy 420.141146 -48.414432) (xy 420.141146 -47.906432) (xy 420.522146 -47.906432) (xy 420.522146 -48.414432)
				)
			)
		)
		(zone
			(layer "B.Cu")
			(hatch none 0.5)
			(connect_pads
				(clearance 0)
			)
			(min_thickness 0.25)
			(keepout
				(tracks not_allowed)
				(vias allowed)
				(pads allowed)
				(copperpour not_allowed)
				(footprints allowed)
			)
			(placement
				(enabled no)
				(sheetname "")
			)
			(fill
				(thermal_gap 0.5)
				(thermal_bridge_width 0.5)
				(island_removal_mode 0)
			)
			(polygon
				(pts
					(xy 420.522146 -48.414432) (xy 420.522146 -47.906432) (xy 420.141146 -47.906432) (xy 420.141146 -48.414432)
				)
			)
		)
	)
	(footprint ""
		(layer "B.Cu")
		(at 266.104624 -68.184014 180)
		(property "Reference" "C5P39"
			(at 0 0 0)
			(layer "B.SilkS")
			(hide yes)
			(effects
				(font
					(size 1.27 1.27)
				)
				(justify mirror)
			)
		)
		(property "Value" ""
			(at 0 0 0)
			(layer "B.Fab")
			(effects
				(font
					(size 1.27 1.27)
				)
				(justify mirror)
			)
		)
		(duplicate_pad_numbers_are_jumpers no)
		(fp_poly
			(pts
				(xy 0.7239 -0.2159) (xy -0.7239 -0.2159) (xy -0.7239 1.9939) (xy 0.7239 1.9939)
			)
			(stroke
				(width 0)
				(type default)
			)
			(fill no)
			(layer "B.CrtYd")
		)
		(fp_line
			(start 0.7239 1.9939)
			(end -0.7239 1.9939)
			(stroke
				(width 0.1)
				(type default)
			)
			(layer "B.Fab")
		)
		(fp_line
			(start 0.7239 -0.2159)
			(end 0.7239 1.9939)
			(stroke
				(width 0.1)
				(type default)
			)
			(layer "B.Fab")
		)
		(fp_line
			(start -0.7239 1.9939)
			(end -0.7239 -0.2159)
			(stroke
				(width 0.1)
				(type default)
			)
			(layer "B.Fab")
		)
		(fp_line
			(start -0.7239 -0.2159)
			(end 0.7239 -0.2159)
			(stroke
				(width 0.1)
				(type default)
			)
			(layer "B.Fab")
		)
		(pad "1" smd rect
			(at 0 0)
			(size 1.27 1.016)
			(layers "B.Cu" "B.Mask" "B.Paste")
			(net "PVDDQ_ABC")
		)
		(pad "2" smd rect
			(at 0 1.778)
			(size 1.27 1.016)
			(layers "B.Cu" "B.Mask" "B.Paste")
			(net "GND")
		)
		(zone
			(layer "B.Cu")
			(hatch none 0.5)
			(connect_pads
				(clearance 0)
			)
			(min_thickness 0.25)
			(keepout
				(tracks not_allowed)
				(vias allowed)
				(pads allowed)
				(copperpour not_allowed)
				(footprints allowed)
			)
			(placement
				(enabled no)
				(sheetname "")
			)
			(fill
				(thermal_gap 0.5)
				(thermal_bridge_width 0.5)
				(island_removal_mode 0)
			)
			(polygon
				(pts
					(xy 265.469624 -68.692014) (xy 266.739624 -68.692014) (xy 266.739624 -69.454014) (xy 265.469624 -69.454014)
				)
			)
		)
	)
	(footprint ""
		(layer "B.Cu")
		(at 402.3995 -42.926 -90)
		(property "Reference" "R25W70"
			(at 0.8382 -0.67818 270)
			(unlocked yes)
			(layer "B.SilkS")
			(effects
				(font
					(size 0.4064 0.254)
					(thickness 0.1524)
				)
				(justify left mirror)
			)
		)
		(property "Value" ""
			(at 0 0 90)
			(layer "B.Fab")
			(effects
				(font
					(size 1.27 1.27)
				)
				(justify mirror)
			)
		)
		(duplicate_pad_numbers_are_jumpers no)
		(fp_poly
			(pts
				(xy 0.2794 -0.1016) (xy -0.2794 -0.1016) (xy -0.2794 0.9906) (xy 0.2794 0.9906)
			)
			(stroke
				(width 0)
				(type default)
			)
			(fill no)
			(layer "B.CrtYd")
		)
		(fp_line
			(start -0.2794 0.9906)
			(end -0.2794 -0.1016)
			(stroke
				(width 0.1)
				(type default)
			)
			(layer "B.Fab")
		)
		(fp_line
			(start 0.2794 0.9906)
			(end -0.2794 0.9906)
			(stroke
				(width 0.1)
				(type default)
			)
			(layer "B.Fab")
		)
		(fp_line
			(start -0.2794 -0.1016)
			(end 0.2794 -0.1016)
			(stroke
				(width 0.1)
				(type default)
			)
			(layer "B.Fab")
		)
		(fp_line
			(start 0.2794 -0.1016)
			(end 0.2794 0.9906)
			(stroke
				(width 0.1)
				(type default)
			)
			(layer "B.Fab")
		)
		(pad "1" smd rect
			(at 0 0 90)
			(size 0.508 0.508)
			(layers "B.Cu" "B.Mask" "B.Paste")
			(net "FM_CPU0_FIVR_FAULT_LVT3_R_N")
		)
		(pad "2" smd rect
			(at 0 0.889 90)
			(size 0.508 0.508)
			(layers "B.Cu" "B.Mask" "B.Paste")
			(net "FM_CPU0_FIVR_FAULT_LVT3_N")
		)
		(zone
			(layer "B.Cu")
			(hatch none 0.5)
			(connect_pads
				(clearance 0)
			)
			(min_thickness 0.25)
			(keepout
				(tracks not_allowed)
				(vias allowed)
				(pads allowed)
				(copperpour not_allowed)
				(footprints allowed)
			)
			(placement
				(enabled no)
				(sheetname "")
			)
			(fill
				(thermal_gap 0.5)
				(thermal_bridge_width 0.5)
				(island_removal_mode 0)
			)
			(polygon
				(pts
					(xy 401.7645 -42.672) (xy 401.7645 -43.18) (xy 402.1455 -43.18) (xy 402.1455 -42.672)
				)
			)
		)
		(zone
			(layer "B.Cu")
			(hatch none 0.5)
			(connect_pads
				(clearance 0)
			)
			(min_thickness 0.25)
			(keepout
				(tracks allowed)
				(vias not_allowed)
				(pads allowed)
				(copperpour not_allowed)
				(footprints allowed)
			)
			(placement
				(enabled no)
				(sheetname "")
			)
			(fill
				(thermal_gap 0.5)
				(thermal_bridge_width 0.5)
				(island_removal_mode 0)
			)
			(polygon
				(pts
					(xy 402.1455 -42.672) (xy 402.1455 -43.18) (xy 401.7645 -43.18) (xy 401.7645 -42.672)
				)
			)
		)
	)
)
